(kicad_pcb
	(version 20241229)
	(generator "pcbnew")
	(generator_version "9.0")
	(general
		(thickness 1.63)
		(legacy_teardrops no)
	)
	(paper "A4")
	(title_block
		(title "CM4 Baseboard")
		(date "2026-01-05")
		(rev "1.1.1")
		(company "Antmicro Ltd")
		(comment 1 "www.antmicro.com")
		(comment 9 "footprints 122-126 of 506")
	)
	(layers
		(0 "F.Cu" signal)
		(4 "In1.Cu" power)
		(6 "In2.Cu" power)
		(8 "In3.Cu" signal)
		(10 "In4.Cu" signal)
		(2 "B.Cu" signal)
		(9 "F.Adhes" user "F.Adhesive")
		(11 "B.Adhes" user "B.Adhesive")
		(13 "F.Paste" user)
		(15 "B.Paste" user)
		(5 "F.SilkS" user "F.Silkscreen")
		(7 "B.SilkS" user "B.Silkscreen")
		(1 "F.Mask" user)
		(3 "B.Mask" user)
		(17 "Dwgs.User" user "User.Drawings")
		(19 "Cmts.User" user "User.Comments")
		(21 "Eco1.User" user "User.Eco1")
		(23 "Eco2.User" user "User.Eco2")
		(25 "Edge.Cuts" user)
		(27 "Margin" user)
		(31 "F.CrtYd" user "F.Courtyard")
		(29 "B.CrtYd" user "B.Courtyard")
		(35 "F.Fab" user)
		(33 "B.Fab" user)
	)
	(footprint "antmicro-footprints:L_TE_0603_1811Metric"
		(layer "F.Cu")
		(at 68.35 176.79 -90)
		(property "Reference" "L801"
			(at -1.39 1.45 90)
			(layer "F.SilkS")
			(effects
				(font
					(size 0.7 0.7)
					(thickness 0.15)
				)
				(justify right top)
			)
		)
		(property "Value" "L_160n_0.28A_0603"
			(at -1.41 1.759999 90)
			(layer "F.Fab")
			(effects
				(font
					(size 0.7 0.7)
					(thickness 0.15)
				)
				(justify right top)
			)
		)
		(property "Datasheet" "https://www.te.com/commerce/DocumentDelivery/DDEController?Action=showdoc&DocId=Data+Sheet%7F1773163%7FE%7Fpdf%7FEnglish%7FENG_DS_1773163_E.pdf"
			(at 0 0 90)
			(layer "F.Fab")
			(effects
				(font
					(size 0.7 0.7)
					(thickness 0.15)
				)
				(justify right top)
			)
		)
		(property "Description" "RF Inductor - 160 nH, 5%, 280 mA, 0603"
			(at 0 0 90)
			(layer "F.Fab")
			(effects
				(font
					(size 0.7 0.7)
					(thickness 0.15)
				)
				(justify right top)
			)
		)
		(property "Val" "160 nH"
			(at 0 0 270)
			(unlocked yes)
			(layer "F.Fab")
			(hide yes)
			(effects
				(font
					(size 1 1)
					(thickness 0.15)
				)
			)
		)
		(property "Manufacturer" "TE Connectivity"
			(at 0 0 270)
			(unlocked yes)
			(layer "F.Fab")
			(hide yes)
			(effects
				(font
					(size 1 1)
					(thickness 0.15)
				)
			)
		)
		(property "MPN" "36501JR16JTDG"
			(at 0 0 270)
			(unlocked yes)
			(layer "F.Fab")
			(hide yes)
			(effects
				(font
					(size 1 1)
					(thickness 0.15)
				)
			)
		)
		(property "ISat" ""
			(at 0 0 270)
			(unlocked yes)
			(layer "F.Fab")
			(hide yes)
			(effects
				(font
					(size 1 1)
					(thickness 0.15)
				)
			)
		)
		(property "IMax" "0.28 A"
			(at 0 0 270)
			(unlocked yes)
			(layer "F.Fab")
			(hide yes)
			(effects
				(font
					(size 1 1)
					(thickness 0.15)
				)
			)
		)
		(property "Size" "1.8 x 1.12"
			(at 0 0 270)
			(unlocked yes)
			(layer "F.Fab")
			(hide yes)
			(effects
				(font
					(size 1 1)
					(thickness 0.15)
				)
			)
		)
		(property "Author" "Antmicro"
			(at 0 0 270)
			(unlocked yes)
			(layer "F.Fab")
			(hide yes)
			(effects
				(font
					(size 1 1)
					(thickness 0.15)
				)
			)
		)
		(property "License" "Apache-2.0"
			(at 0 0 270)
			(unlocked yes)
			(layer "F.Fab")
			(hide yes)
			(effects
				(font
					(size 1 1)
					(thickness 0.15)
				)
			)
		)
		(sheetname "/Peripherals/")
		(sheetfile "peripherals.kicad_sch")
		(attr smd)
		(fp_line
			(start -0.15 0.4)
			(end 0.15 0.4)
			(stroke
				(width 0.15)
				(type solid)
			)
			(layer "F.SilkS")
		)
		(fp_line
			(start -0.15 -0.4)
			(end 0.15 -0.4)
			(stroke
				(width 0.15)
				(type solid)
			)
			(layer "F.SilkS")
		)
		(fp_poly
			(pts
				(xy -1.06 -0.66) (xy 1.06 -0.66) (xy 1.06 0.66) (xy -1.06 0.66)
			)
			(stroke
				(width 0.05)
				(type solid)
			)
			(fill no)
			(layer "F.CrtYd")
		)
		(fp_poly
			(pts
				(xy -0.8 -0.4) (xy 0.8 -0.4) (xy 0.8 0.4) (xy -0.8 0.4)
			)
			(stroke
				(width 0.15)
				(type solid)
			)
			(fill no)
			(layer "F.Fab")
		)
		(fp_text user "${REFERENCE}"
			(at -1.41 2.960001 90)
			(layer "F.Fab")
			(effects
				(font
					(size 0.7 0.7)
					(thickness 0.15)
				)
				(justify right top)
			)
		)
		(fp_text user "Author: Antmicro"
			(at -1.41 4.16 90)
			(layer "F.Fab")
			(effects
				(font
					(size 0.7 0.7)
					(thickness 0.15)
				)
				(justify right top)
			)
		)
		(fp_text user "License: Apache-2.0"
			(at -1.41 5.36 90)
			(layer "F.Fab")
			(effects
				(font
					(size 0.7 0.7)
					(thickness 0.15)
				)
				(justify right top)
			)
		)
		(pad "1" smd roundrect
			(at -0.64 0 270)
			(size 0.64 1.02)
			(layers "F.Cu" "F.Mask" "F.Paste")
			(roundrect_rratio 0.2)
			(net 325 "Net-(U801-TX1)")
			(pintype "passive")
		)
		(pad "2" smd roundrect
			(at 0.64 0 270)
			(size 0.64 1.02)
			(layers "F.Cu" "F.Mask" "F.Paste")
			(roundrect_rratio 0.2)
			(net 109 "Net-(C816-Pad2)")
			(pintype "passive")
		)
	)
	(footprint "antmicro-footprints:TP_SMD_0.75mm"
		(layer "F.Cu")
		(at 134.65 153.65)
		(property "Reference" "TP604"
			(at -2.95 -0.7 0)
			(layer "F.SilkS")
			(effects
				(font
					(size 0.7 0.7)
					(thickness 0.15)
				)
				(justify left bottom)
			)
		)
		(property "Value" "TP_0.75mm_SMD"
			(at 0 1.2 0)
			(layer "F.Fab")
			(effects
				(font
					(size 0.7 0.7)
					(thickness 0.15)
				)
				(justify left bottom)
			)
		)
		(property "MPN" ""
			(at 0 0 0)
			(unlocked yes)
			(layer "F.Fab")
			(hide yes)
			(effects
				(font
					(size 1 1)
					(thickness 0.15)
				)
			)
		)
		(property "Manufacturer" ""
			(at 0 0 0)
			(unlocked yes)
			(layer "F.Fab")
			(hide yes)
			(effects
				(font
					(size 1 1)
					(thickness 0.15)
				)
			)
		)
		(property "Author" "Antmicro"
			(at 0 0 0)
			(unlocked yes)
			(layer "F.Fab")
			(hide yes)
			(effects
				(font
					(size 1 1)
					(thickness 0.15)
				)
			)
		)
		(property "License" "Apache-2.0"
			(at 0 0 0)
			(unlocked yes)
			(layer "F.Fab")
			(hide yes)
			(effects
				(font
					(size 1 1)
					(thickness 0.15)
				)
			)
		)
		(sheetname "/CSI/")
		(sheetfile "csi.kicad_sch")
		(attr exclude_from_pos_files exclude_from_bom)
		(fp_circle
			(center 0 0)
			(end 0.475 0)
			(stroke
				(width 0.05)
				(type default)
			)
			(fill no)
			(layer "F.CrtYd")
		)
		(fp_text user "License: Apache-2.0"
			(at -0.4 5.101 0)
			(layer "F.Fab")
			(effects
				(font
					(size 0.7 0.7)
					(thickness 0.15)
				)
				(justify left bottom)
			)
		)
		(fp_text user "${REFERENCE}"
			(at -0.4 2.7 0)
			(layer "F.Fab")
			(effects
				(font
					(size 0.7 0.7)
					(thickness 0.15)
				)
				(justify left bottom)
			)
		)
		(fp_text user "Author: Antmicro"
			(at -0.4 3.901 0)
			(layer "F.Fab")
			(effects
				(font
					(size 0.7 0.7)
					(thickness 0.15)
				)
				(justify left bottom)
			)
		)
		(pad "1" smd circle
			(at 0 0)
			(size 0.75 0.75)
			(layers "F.Cu" "F.Mask")
			(net 19 "/CSI/CSI_3V3")
			(pinfunction "1")
			(pintype "passive")
		)
	)
	(footprint "antmicro-footprints:R_0402_1005Metric"
		(layer "F.Cu")
		(at 117.88 156.7915 180)
		(descr "Resistor SMD 0402")
		(tags "resistor SMD 0402")
		(property "Reference" "R221"
			(at -3.5 -0.325 180)
			(layer "F.SilkS")
			(effects
				(font
					(size 0.7 0.7)
					(thickness 0.15)
				)
				(justify left bottom)
			)
		)
		(property "Value" "R_0R_0402"
			(at -1.011843 1.772047 180)
			(layer "F.Fab")
			(effects
				(font
					(size 0.7 0.7)
					(thickness 0.15)
				)
				(justify left bottom)
			)
		)
		(property "Datasheet" "https://industrial.panasonic.com/cdbs/www-data/pdf/RDA0000/AOA0000C301.pdf"
			(at 0 0 180)
			(layer "F.Fab")
			(hide yes)
			(effects
				(font
					(size 1.27 1.27)
					(thickness 0.15)
				)
			)
		)
		(property "Manufacturer" "Panasonic"
			(at 0 0 180)
			(unlocked yes)
			(layer "F.Fab")
			(hide yes)
			(effects
				(font
					(size 1 1)
					(thickness 0.15)
				)
			)
		)
		(property "MPN" "ERJ2GE0R00X"
			(at 0 0 180)
			(unlocked yes)
			(layer "F.Fab")
			(hide yes)
			(effects
				(font
					(size 1 1)
					(thickness 0.15)
				)
			)
		)
		(property "Val" "0R"
			(at 0 0 180)
			(unlocked yes)
			(layer "F.Fab")
			(hide yes)
			(effects
				(font
					(size 1 1)
					(thickness 0.15)
				)
			)
		)
		(property "License" "Apache-2.0"
			(at 0 0 180)
			(unlocked yes)
			(layer "F.Fab")
			(hide yes)
			(effects
				(font
					(size 1 1)
					(thickness 0.15)
				)
			)
		)
		(property "Author" "Antmicro"
			(at 0 0 180)
			(unlocked yes)
			(layer "F.Fab")
			(hide yes)
			(effects
				(font
					(size 1 1)
					(thickness 0.15)
				)
			)
		)
		(property "Tolerance" "~"
			(at 0 0 180)
			(unlocked yes)
			(layer "F.Fab")
			(hide yes)
			(effects
				(font
					(size 1 1)
					(thickness 0.15)
				)
			)
		)
		(property "Current" "1A"
			(at 0 0 180)
			(unlocked yes)
			(layer "F.Fab")
			(hide yes)
			(effects
				(font
					(size 1 1)
					(thickness 0.15)
				)
			)
		)
		(sheetname "/Compute module/")
		(sheetfile "compute-module.kicad_sch")
		(attr smd)
		(fp_rect
			(start -0.925 -0.47)
			(end 0.925 0.47)
			(stroke
				(width 0.05)
				(type default)
			)
			(fill no)
			(layer "F.CrtYd")
		)
		(fp_rect
			(start -0.5 -0.25)
			(end 0.5 0.25)
			(stroke
				(width 0.15)
				(type solid)
			)
			(fill no)
			(layer "F.Fab")
		)
		(fp_text user "Author: Antmicro"
			(at -0.95 4.169 180)
			(layer "F.Fab")
			(effects
				(font
					(size 0.7 0.7)
					(thickness 0.15)
				)
				(justify left bottom)
			)
		)
		(fp_text user "License: Apache-2.0"
			(at -0.95 5.169 180)
			(layer "F.Fab")
			(effects
				(font
					(size 0.7 0.7)
					(thickness 0.15)
				)
				(justify left bottom)
			)
		)
		(fp_text user "${REFERENCE}"
			(at -0.95 3.168 180)
			(layer "F.Fab")
			(effects
				(font
					(size 0.7 0.7)
					(thickness 0.15)
				)
				(justify left bottom)
			)
		)
		(pad "1" smd roundrect
			(at -0.48 0 180)
			(size 0.59 0.64)
			(layers "F.Cu" "F.Mask" "F.Paste")
			(roundrect_rratio 0.25)
			(net 164 "/Compute module/NVMe.TX2_N")
			(pintype "passive")
		)
		(pad "2" smd roundrect
			(at 0.48 0 180)
			(size 0.59 0.64)
			(layers "F.Cu" "F.Mask" "F.Paste")
			(roundrect_rratio 0.25)
			(net 152 "/Compute module/T2_N")
			(pintype "passive")
		)
	)
	(footprint "antmicro-footprints:R_0402_1005Metric"
		(layer "F.Cu")
		(at 56.392962 134.3665 90)
		(descr "Resistor SMD 0402")
		(tags "resistor SMD 0402")
		(property "Reference" "R419"
			(at -1.985 3.495 90)
			(layer "F.SilkS")
			(effects
				(font
					(size 0.7 0.7)
					(thickness 0.15)
				)
				(justify left bottom)
			)
		)
		(property "Value" "R_470k_0402"
			(at -1.011843 1.772047 90)
			(layer "F.Fab")
			(effects
				(font
					(size 0.7 0.7)
					(thickness 0.15)
				)
				(justify left bottom)
			)
		)
		(property "Datasheet" "https://www.bourns.com/docs/product-datasheets/cr.pdf"
			(at 0 0 90)
			(layer "F.Fab")
			(hide yes)
			(effects
				(font
					(size 1.27 1.27)
					(thickness 0.15)
				)
			)
		)
		(property "Manufacturer" "Bourns"
			(at 0 0 90)
			(unlocked yes)
			(layer "F.Fab")
			(hide yes)
			(effects
				(font
					(size 1 1)
					(thickness 0.15)
				)
			)
		)
		(property "MPN" "CR0402-FX-4703GLF"
			(at 0 0 90)
			(unlocked yes)
			(layer "F.Fab")
			(hide yes)
			(effects
				(font
					(size 1 1)
					(thickness 0.15)
				)
			)
		)
		(property "Val" "470k"
			(at 0 0 90)
			(unlocked yes)
			(layer "F.Fab")
			(hide yes)
			(effects
				(font
					(size 1 1)
					(thickness 0.15)
				)
			)
		)
		(property "License" "Apache-2.0"
			(at 0 0 90)
			(unlocked yes)
			(layer "F.Fab")
			(hide yes)
			(effects
				(font
					(size 1 1)
					(thickness 0.15)
				)
			)
		)
		(property "Author" "Antmicro"
			(at 0 0 90)
			(unlocked yes)
			(layer "F.Fab")
			(hide yes)
			(effects
				(font
					(size 1 1)
					(thickness 0.15)
				)
			)
		)
		(property "Tolerance" "1%"
			(at 0 0 90)
			(unlocked yes)
			(layer "F.Fab")
			(hide yes)
			(effects
				(font
					(size 1 1)
					(thickness 0.15)
				)
			)
		)
		(sheetname "/Ethernet/")
		(sheetfile "ethernet.kicad_sch")
		(attr smd exclude_from_pos_files exclude_from_bom dnp)
		(fp_rect
			(start -0.925 -0.47)
			(end 0.925 0.47)
			(stroke
				(width 0.05)
				(type default)
			)
			(fill no)
			(layer "F.CrtYd")
		)
		(fp_rect
			(start -0.5 -0.25)
			(end 0.5 0.25)
			(stroke
				(width 0.15)
				(type solid)
			)
			(fill no)
			(layer "F.Fab")
		)
		(fp_text user "Author: Antmicro"
			(at -0.95 4.169 90)
			(layer "F.Fab")
			(effects
				(font
					(size 0.7 0.7)
					(thickness 0.15)
				)
				(justify left bottom)
			)
		)
		(fp_text user "License: Apache-2.0"
			(at -0.95 5.169 90)
			(layer "F.Fab")
			(effects
				(font
					(size 0.7 0.7)
					(thickness 0.15)
				)
				(justify left bottom)
			)
		)
		(fp_text user "${REFERENCE}"
			(at -0.95 3.168 90)
			(layer "F.Fab")
			(effects
				(font
					(size 0.7 0.7)
					(thickness 0.15)
				)
				(justify left bottom)
			)
		)
		(pad "1" smd roundrect
			(at -0.48 0 90)
			(size 0.59 0.64)
			(layers "F.Cu" "F.Mask" "F.Paste")
			(roundrect_rratio 0.25)
			(net 126 "/Ethernet/ULS-12_CTRL")
			(pintype "passive")
		)
		(pad "2" smd roundrect
			(at 0.48 0 90)
			(size 0.59 0.64)
			(layers "F.Cu" "F.Mask" "F.Paste")
			(roundrect_rratio 0.25)
			(net 33 "/Ethernet/VDD")
			(pintype "passive")
		)
	)
	(footprint "antmicro-footprints:C_0402_1005Metric"
		(layer "F.Cu")
		(at 94.092962 147.8415)
		(descr "Capacitor SMD 0402")
		(tags "capacitor SMD 0402")
		(property "Reference" "C209"
			(at 2.025 0.525 0)
			(layer "F.SilkS")
			(effects
				(font
					(size 0.7 0.7)
					(thickness 0.15)
				)
				(justify left bottom)
			)
		)
		(property "Value" "C_10u_0402"
			(at -1.022927 2.155213 0)
			(layer "F.Fab")
			(effects
				(font
					(size 0.7 0.7)
					(thickness 0.15)
				)
				(justify left bottom)
			)
		)
		(property "Datasheet" "https://www.yageo.com/en/Chart/Download/pdf/CC0402MRX5R5BB106"
			(at 0 0 0)
			(layer "F.Fab")
			(hide yes)
			(effects
				(font
					(size 1.27 1.27)
					(thickness 0.15)
				)
			)
		)
		(property "MPN" "CC0402MRX5R5BB106"
			(at 0 0 0)
			(unlocked yes)
			(layer "F.Fab")
			(hide yes)
			(effects
				(font
					(size 1 1)
					(thickness 0.15)
				)
			)
		)
		(property "Manufacturer" "YAGEO"
			(at 0 0 0)
			(unlocked yes)
			(layer "F.Fab")
			(hide yes)
			(effects
				(font
					(size 1 1)
					(thickness 0.15)
				)
			)
		)
		(property "License" "Apache-2.0"
			(at 0 0 0)
			(unlocked yes)
			(layer "F.Fab")
			(hide yes)
			(effects
				(font
					(size 1 1)
					(thickness 0.15)
				)
			)
		)
		(property "Author" "Antmicro"
			(at 0 0 0)
			(unlocked yes)
			(layer "F.Fab")
			(hide yes)
			(effects
				(font
					(size 1 1)
					(thickness 0.15)
				)
			)
		)
		(property "Val" "10u"
			(at 0 0 0)
			(unlocked yes)
			(layer "F.Fab")
			(hide yes)
			(effects
				(font
					(size 1 1)
					(thickness 0.15)
				)
			)
		)
		(property "Voltage" ""
			(at 0 0 0)
			(unlocked yes)
			(layer "F.Fab")
			(hide yes)
			(effects
				(font
					(size 1 1)
					(thickness 0.15)
				)
			)
		)
		(property "Dielectric" ""
			(at 0 0 0)
			(unlocked yes)
			(layer "F.Fab")
			(hide yes)
			(effects
				(font
					(size 1 1)
					(thickness 0.15)
				)
			)
		)
		(sheetname "/Compute module/")
		(sheetfile "compute-module.kicad_sch")
		(attr smd)
		(fp_rect
			(start -0.925 -0.47)
			(end 0.925 0.47)
			(stroke
				(width 0.05)
				(type default)
			)
			(fill no)
			(layer "F.CrtYd")
		)
		(fp_line
			(start -0.494 -0.25)
			(end 0.504 -0.25)
			(stroke
				(width 0.15)
				(type solid)
			)
			(layer "F.Fab")
		)
		(fp_line
			(start -0.494 0.248)
			(end -0.494 -0.25)
			(stroke
				(width 0.15)
				(type solid)
			)
			(layer "F.Fab")
		)
		(fp_line
			(start 0.504 -0.25)
			(end 0.504 0.248)
			(stroke
				(width 0.15)
				(type solid)
			)
			(layer "F.Fab")
		)
		(fp_line
			(start 0.504 0.248)
			(end -0.494 0.248)
			(stroke
				(width 0.15)
				(type solid)
			)
			(layer "F.Fab")
		)
		(fp_text user "Author: Antmicro"
			(at -0.939 3.399 0)
			(layer "F.Fab")
			(effects
				(font
					(size 0.7 0.7)
					(thickness 0.15)
				)
				(justify left bottom)
			)
		)
		(fp_text user "${REFERENCE}"
			(at -0.939 4.599 0)
			(layer "F.Fab")
			(effects
				(font
					(size 0.7 0.7)
					(thickness 0.15)
				)
				(justify left bottom)
			)
		)
		(fp_text user "License: Apache-2.0"
			(at -0.939 5.799 0)
			(layer "F.Fab")
			(effects
				(font
					(size 0.7 0.7)
					(thickness 0.15)
				)
				(justify left bottom)
			)
		)
		(pad "1" smd roundrect
			(at -0.48 0)
			(size 0.59 0.64)
			(layers "F.Cu" "F.Mask" "F.Paste")
			(roundrect_rratio 0.25)
			(net 3 "GND")
			(pintype "passive")
		)
		(pad "2" smd roundrect
			(at 0.48 0)
			(size 0.59 0.64)
			(layers "F.Cu" "F.Mask" "F.Paste")
			(roundrect_rratio 0.25)
			(net 9 "+3V3")
			(pintype "passive")
		)
	)
)
